(kicad_pcb
	(version 20260206)
	(generator "pcbnew")
	(generator_version "10.0")
	(general
		(thickness 1.6)
		(legacy_teardrops no)
	)
	(paper "A4")
	(title_block
		(title "Wiwynn_Tioga_Pass_MB.brd")
		(comment 1 "Tioga Pass / footprints 1311-1316 of 4770")
	)
	(layers
		(0 "F.Cu" signal "TOP")
		(4 "In1.Cu" signal "L2GND")
		(6 "In2.Cu" signal "L3")
		(8 "In3.Cu" signal "L4GND")
		(10 "In4.Cu" signal "L5")
		(12 "In5.Cu" signal "L6GND")
		(14 "In6.Cu" signal "L7VCC")
		(16 "In7.Cu" signal "L8VCC")
		(18 "In8.Cu" signal "L9GND")
		(20 "In9.Cu" signal "L10")
		(22 "In10.Cu" signal "L11GND")
		(24 "In11.Cu" signal "L12")
		(26 "In12.Cu" signal "L13GND")
		(2 "B.Cu" signal "BOTTOM")
		(9 "F.Adhes" user "F.Adhesive")
		(11 "B.Adhes" user "B.Adhesive")
		(13 "F.Paste" user "Package Geometry/Pastemask Top")
		(15 "B.Paste" user "Package Geometry/Pastemask Bottom")
		(5 "F.SilkS" user "Ref Des/Silkscreen Top")
		(7 "B.SilkS" user "Ref Des/Silkscreen Bottom")
		(1 "F.Mask" user "Board Geometry/Soldermask Top")
		(3 "B.Mask" user "Board Geometry/Soldermask Bottom")
		(17 "Dwgs.User" user "User.Drawings")
		(19 "Cmts.User" user "User.Comments")
		(21 "Eco1.User" user "User.Eco1")
		(23 "Eco2.User" user "User.Eco2")
		(25 "Edge.Cuts" user "Board Geometry/Outline")
		(27 "Margin" user)
		(31 "F.CrtYd" user "Package Geometry/Place Bound Top")
		(29 "B.CrtYd" user "Package Geometry/Place Bound Bottom")
		(35 "F.Fab" user "Ref Des/Assembly Top")
		(33 "B.Fab" user "Ref Des/Assembly Bottom")
	)
	(footprint ""
		(layer "F.Cu")
		(at 33.925002 -81.423764 90)
		(property "Reference" "EU1D1"
			(at 3.334766 -1.565402 0)
			(unlocked yes)
			(layer "F.SilkS")
			(effects
				(font
					(size 0.7874 0.5842)
					(thickness 0.1524)
				)
			)
		)
		(property "Value" ""
			(at 0 0 90)
			(layer "F.Fab")
			(effects
				(font
					(size 1.27 1.27)
				)
			)
		)
		(duplicate_pad_numbers_are_jumpers no)
		(fp_line
			(start 2.9718 -3.5052)
			(end 2.9718 3.429)
			(stroke
				(width 0.1524)
				(type default)
			)
			(layer "F.SilkS")
		)
		(fp_line
			(start -3.0099 -3.5052)
			(end 2.9718 -3.5052)
			(stroke
				(width 0.1524)
				(type default)
			)
			(layer "F.SilkS")
		)
		(fp_line
			(start 2.9718 3.429)
			(end -3.0099 3.429)
			(stroke
				(width 0.1524)
				(type default)
			)
			(layer "F.SilkS")
		)
		(fp_line
			(start -3.0099 3.429)
			(end -3.0099 -3.5052)
			(stroke
				(width 0.1524)
				(type default)
			)
			(layer "F.SilkS")
		)
		(fp_circle
			(center -3.057398 -2.678684)
			(end -3.057398 -2.551684)
			(stroke
				(width 0.254)
				(type default)
			)
			(fill no)
			(layer "F.SilkS")
		)
		(fp_poly
			(pts
				(xy -2.9972 -3.4925) (xy -2.9972 -2.6924) (xy -2.1971 -3.4925)
			)
			(stroke
				(width 0)
				(type default)
			)
			(fill yes)
			(layer "F.SilkS")
		)
		(fp_poly
			(pts
				(xy -2.549906 -3.050032) (xy -2.549906 3.050032) (xy 2.549906 3.050032) (xy 2.549906 -3.050032)
			)
			(stroke
				(width 0)
				(type default)
			)
			(fill no)
			(layer "F.CrtYd")
		)
		(fp_line
			(start 2.549906 -3.050032)
			(end 2.549906 3.050032)
			(stroke
				(width 0.1)
				(type default)
			)
			(layer "F.Fab")
		)
		(fp_line
			(start -2.549906 -3.050032)
			(end 2.549906 -3.050032)
			(stroke
				(width 0.1)
				(type default)
			)
			(layer "F.Fab")
		)
		(fp_line
			(start 2.549906 3.050032)
			(end -2.549906 3.050032)
			(stroke
				(width 0.1)
				(type default)
			)
			(layer "F.Fab")
		)
		(fp_line
			(start -2.549906 3.050032)
			(end -2.549906 -3.050032)
			(stroke
				(width 0.1)
				(type default)
			)
			(layer "F.Fab")
		)
		(fp_circle
			(center -3.057398 -2.678684)
			(end -3.057398 -2.551684)
			(stroke
				(width 0.254)
				(type default)
			)
			(fill no)
			(layer "F.Fab")
		)
		(pad "1" smd rect
			(at -2.39522 -2.279904 90)
			(size 0.7112 0.254)
			(layers "F.Cu" "F.Mask" "F.Paste")
			(net "PVCCIN_CPU1")
		)
		(pad "2" smd rect
			(at -2.39522 -1.83007 90)
			(size 0.7112 0.254)
			(layers "F.Cu" "F.Mask" "F.Paste")
			(net "GND")
		)
		(pad "3" smd rect
			(at -2.39522 -1.379982 90)
			(size 0.7112 0.254)
			(layers "F.Cu" "F.Mask" "F.Paste")
			(net "VR_PVCCIN_CPU1_PH4_VCIN")
		)
		(pad "4" smd rect
			(at -2.39522 -0.929894 90)
			(size 0.7112 0.254)
			(layers "F.Cu" "F.Mask" "F.Paste")
			(net "P5V_STBY")
		)
		(pad "5" smd rect
			(at -2.39522 -0.48006 90)
			(size 0.7112 0.254)
			(layers "F.Cu" "F.Mask" "F.Paste")
			(net "GND")
		)
		(pad "6" smd rect
			(at -2.39522 -0.029972 90)
			(size 0.7112 0.254)
			(layers "F.Cu" "F.Mask" "F.Paste")
			(net "TP_PVCCIN_CPU1_PH4_GL_0")
		)
		(pad "7" smd custom
			(at 0.016764 1.145032 90)
			(size 0.53975 0.53975)
			(layers "F.Cu" "F.Mask" "F.Paste")
			(net "GND")
			(options
				(clearance outline)
				(anchor circle)
			)
			(primitives
				(gr_poly
					(pts
						(xy -2.7051 1.0795) (xy -2.7051 -0.3683) (xy -0.9271 -0.3683) (xy -0.9271 -1.0795) (xy 2.7051 -1.0795)
						(xy 2.7051 1.0795)
					)
					(width 0)
					(fill yes)
				)
			)
		)
		(pad "10" smd rect
			(at -0.008382 2.874772 90)
			(size 4.3434 0.6096)
			(layers "F.Cu" "F.Mask" "F.Paste")
			(net "VR_PVCCIN_CPU1_PHASE4")
		)
		(pad "25" smd rect
			(at 1.548384 -1.283208 90)
			(size 2.3368 2.0066)
			(layers "F.Cu" "F.Mask" "F.Paste")
			(net "VR_FET_SW_P12V_STBY_PVCCIN_CPU1")
		)
		(pad "30" smd rect
			(at 2.050034 -2.895092 90)
			(size 0.254 0.7112)
			(layers "F.Cu" "F.Mask" "F.Paste")
			(net "VR_FET_SW_P12V_STBY_PVCCIN_CPU1")
		)
		(pad "31" smd rect
			(at 1.599946 -2.895092 90)
			(size 0.254 0.7112)
			(layers "F.Cu" "F.Mask" "F.Paste")
			(net "Net_358")
		)
		(pad "32" smd rect
			(at 1.150112 -2.895092 90)
			(size 0.254 0.7112)
			(layers "F.Cu" "F.Mask" "F.Paste")
			(net "VR_PVCCIN_CPU1_PH4_PHASE")
		)
		(pad "33" smd rect
			(at 0.700024 -2.895092 90)
			(size 0.254 0.7112)
			(layers "F.Cu" "F.Mask" "F.Paste")
			(net "VR_PVCCIN_CPU1_PH4_BOOT_R")
		)
		(pad "34" smd rect
			(at 0.249936 -2.895092 90)
			(size 0.254 0.7112)
			(layers "F.Cu" "F.Mask" "F.Paste")
			(net "VR_PVCCIN_CPU1_PWM4")
		)
		(pad "35" smd rect
			(at -0.199898 -2.895092 90)
			(size 0.254 0.7112)
			(layers "F.Cu" "F.Mask" "F.Paste")
			(net "P5V_STBY")
		)
		(pad "36" smd rect
			(at -0.649986 -2.895092 90)
			(size 0.254 0.7112)
			(layers "F.Cu" "F.Mask" "F.Paste")
			(net "A_TSENSE_PVCCIN_CPU1")
		)
		(pad "37" smd rect
			(at -1.100074 -2.895092 90)
			(size 0.254 0.7112)
			(layers "F.Cu" "F.Mask" "F.Paste")
			(net "VR_PVCCIN_CPU1_PH4_OCSET")
		)
		(pad "38" smd rect
			(at -1.549908 -2.895092 90)
			(size 0.254 0.7112)
			(layers "F.Cu" "F.Mask" "F.Paste")
			(net "ISENSE_PVCCIN_CPU1_PH4_IMON")
		)
		(pad "39" smd rect
			(at -1.999996 -2.895092 90)
			(size 0.254 0.7112)
			(layers "F.Cu" "F.Mask" "F.Paste")
			(net "VR_PVCCIN_CPU1_AIREF4")
		)
		(pad "40" smd rect
			(at -0.871728 -1.283208 90)
			(size 1.8034 2.0066)
			(layers "F.Cu" "F.Mask" "F.Paste")
			(net "GND")
		)
		(pad "41" smd rect
			(at -1.533906 0.247904 90)
			(size 0.508 0.3556)
			(layers "F.Cu" "F.Mask" "F.Paste")
			(net "TP_PVCCIN_CPU1_PH4_GL_1")
		)
	)
	(footprint ""
		(layer "F.Cu")
		(at 13.438124 -4.426204)
		(property "Reference" "R1G11"
			(at 0 0 0)
			(layer "F.SilkS")
			(hide yes)
			(effects
				(font
					(size 1.27 1.27)
				)
			)
		)
		(property "Value" ""
			(at 0 0 0)
			(layer "F.Fab")
			(effects
				(font
					(size 1.27 1.27)
				)
			)
		)
		(duplicate_pad_numbers_are_jumpers no)
		(fp_poly
			(pts
				(xy -0.2794 -0.1016) (xy 0.2794 -0.1016) (xy 0.2794 0.9906) (xy -0.2794 0.9906)
			)
			(stroke
				(width 0)
				(type default)
			)
			(fill no)
			(layer "F.CrtYd")
		)
		(fp_line
			(start -0.2794 -0.1016)
			(end -0.2794 0.9906)
			(stroke
				(width 0.1)
				(type default)
			)
			(layer "F.Fab")
		)
		(fp_line
			(start -0.2794 0.9906)
			(end 0.2794 0.9906)
			(stroke
				(width 0.1)
				(type default)
			)
			(layer "F.Fab")
		)
		(fp_line
			(start 0.2794 -0.1016)
			(end -0.2794 -0.1016)
			(stroke
				(width 0.1)
				(type default)
			)
			(layer "F.Fab")
		)
		(fp_line
			(start 0.2794 0.9906)
			(end 0.2794 -0.1016)
			(stroke
				(width 0.1)
				(type default)
			)
			(layer "F.Fab")
		)
		(pad "1" smd rect
			(at 0 0)
			(size 0.508 0.508)
			(layers "F.Cu" "F.Mask" "F.Paste")
			(net "P3V3_STBY")
		)
		(pad "2" smd rect
			(at 0 0.889)
			(size 0.508 0.508)
			(layers "F.Cu" "F.Mask" "F.Paste")
			(net "IRQ_PVDDQ_GHJ_VRHOT_LVT3_R_N")
		)
		(zone
			(layer "F.Cu")
			(hatch none 0.5)
			(connect_pads
				(clearance 0)
			)
			(min_thickness 0.25)
			(keepout
				(tracks allowed)
				(vias not_allowed)
				(pads allowed)
				(copperpour not_allowed)
				(footprints allowed)
			)
			(placement
				(enabled no)
				(sheetname "")
			)
			(fill
				(thermal_gap 0.5)
				(thermal_bridge_width 0.5)
				(island_removal_mode 0)
			)
			(polygon
				(pts
					(xy 13.184124 -4.172204) (xy 13.692124 -4.172204) (xy 13.692124 -3.791204) (xy 13.184124 -3.791204)
				)
			)
		)
		(zone
			(layer "F.Cu")
			(hatch none 0.5)
			(connect_pads
				(clearance 0)
			)
			(min_thickness 0.25)
			(keepout
				(tracks not_allowed)
				(vias allowed)
				(pads allowed)
				(copperpour not_allowed)
				(footprints allowed)
			)
			(placement
				(enabled no)
				(sheetname "")
			)
			(fill
				(thermal_gap 0.5)
				(thermal_bridge_width 0.5)
				(island_removal_mode 0)
			)
			(polygon
				(pts
					(xy 13.184124 -3.791204) (xy 13.692124 -3.791204) (xy 13.692124 -4.172204) (xy 13.184124 -4.172204)
				)
			)
		)
	)
	(footprint ""
		(layer "F.Cu")
		(at 346.202 -127.127 90)
		(property "Reference" "C7B12"
			(at 0 0 90)
			(layer "F.SilkS")
			(hide yes)
			(effects
				(font
					(size 1.27 1.27)
				)
			)
		)
		(property "Value" ""
			(at 0 0 90)
			(layer "F.Fab")
			(effects
				(font
					(size 1.27 1.27)
				)
			)
		)
		(duplicate_pad_numbers_are_jumpers no)
		(fp_poly
			(pts
				(xy 0.3048 -0.1016) (xy 0.3048 0.9906) (xy -0.3048 0.9906) (xy -0.3048 -0.1016)
			)
			(stroke
				(width 0)
				(type default)
			)
			(fill no)
			(layer "F.CrtYd")
		)
		(fp_line
			(start 0.3048 -0.1016)
			(end -0.3048 -0.1016)
			(stroke
				(width 0.1)
				(type default)
			)
			(layer "F.Fab")
		)
		(fp_line
			(start -0.3048 -0.1016)
			(end -0.3048 0.9906)
			(stroke
				(width 0.1)
				(type default)
			)
			(layer "F.Fab")
		)
		(fp_line
			(start 0.3048 0.9906)
			(end 0.3048 -0.1016)
			(stroke
				(width 0.1)
				(type default)
			)
			(layer "F.Fab")
		)
		(fp_line
			(start -0.3048 0.9906)
			(end 0.3048 0.9906)
			(stroke
				(width 0.1)
				(type default)
			)
			(layer "F.Fab")
		)
		(pad "1" smd rect
			(at 0 0 90)
			(size 0.508 0.508)
			(layers "F.Cu" "F.Mask" "F.Paste")
			(net "PWRGD_PVPP_DEF_R")
		)
		(pad "2" smd rect
			(at 0 0.889 90)
			(size 0.508 0.508)
			(layers "F.Cu" "F.Mask" "F.Paste")
			(net "GND")
		)
		(zone
			(layer "F.Cu")
			(hatch none 0.5)
			(connect_pads
				(clearance 0)
			)
			(min_thickness 0.25)
			(keepout
				(tracks allowed)
				(vias not_allowed)
				(pads allowed)
				(copperpour not_allowed)
				(footprints allowed)
			)
			(placement
				(enabled no)
				(sheetname "")
			)
			(fill
				(thermal_gap 0.5)
				(thermal_bridge_width 0.5)
				(island_removal_mode 0)
			)
			(polygon
				(pts
					(xy 346.456 -126.873) (xy 346.456 -127.381) (xy 346.837 -127.381) (xy 346.837 -126.873)
				)
			)
		)
		(zone
			(layer "F.Cu")
			(hatch none 0.5)
			(connect_pads
				(clearance 0)
			)
			(min_thickness 0.25)
			(keepout
				(tracks not_allowed)
				(vias allowed)
				(pads allowed)
				(copperpour not_allowed)
				(footprints allowed)
			)
			(placement
				(enabled no)
				(sheetname "")
			)
			(fill
				(thermal_gap 0.5)
				(thermal_bridge_width 0.5)
				(island_removal_mode 0)
			)
			(polygon
				(pts
					(xy 346.837 -126.873) (xy 346.837 -127.381) (xy 346.456 -127.381) (xy 346.456 -126.873)
				)
			)
		)
	)
	(footprint ""
		(layer "F.Cu")
		(at 478.5995 -142.875 -90)
		(property "Reference" "R1L26"
			(at 0 0 270)
			(layer "F.SilkS")
			(hide yes)
			(effects
				(font
					(size 1.27 1.27)
				)
			)
		)
		(property "Value" ""
			(at 0 0 270)
			(layer "F.Fab")
			(effects
				(font
					(size 1.27 1.27)
				)
			)
		)
		(duplicate_pad_numbers_are_jumpers no)
		(fp_poly
			(pts
				(xy -0.2794 -0.1016) (xy 0.2794 -0.1016) (xy 0.2794 0.9906) (xy -0.2794 0.9906)
			)
			(stroke
				(width 0)
				(type default)
			)
			(fill no)
			(layer "F.CrtYd")
		)
		(fp_line
			(start -0.2794 0.9906)
			(end 0.2794 0.9906)
			(stroke
				(width 0.1)
				(type default)
			)
			(layer "F.Fab")
		)
		(fp_line
			(start 0.2794 0.9906)
			(end 0.2794 -0.1016)
			(stroke
				(width 0.1)
				(type default)
			)
			(layer "F.Fab")
		)
		(fp_line
			(start -0.2794 -0.1016)
			(end -0.2794 0.9906)
			(stroke
				(width 0.1)
				(type default)
			)
			(layer "F.Fab")
		)
		(fp_line
			(start 0.2794 -0.1016)
			(end -0.2794 -0.1016)
			(stroke
				(width 0.1)
				(type default)
			)
			(layer "F.Fab")
		)
		(pad "1" smd rect
			(at 0 0 270)
			(size 0.508 0.508)
			(layers "F.Cu" "F.Mask" "F.Paste")
			(net "FM_PWR_BTN_R_N")
		)
		(pad "2" smd rect
			(at 0 0.889 270)
			(size 0.508 0.508)
			(layers "F.Cu" "F.Mask" "F.Paste")
			(net "FM_PWR_BTN_N")
		)
		(zone
			(layer "F.Cu")
			(hatch none 0.5)
			(connect_pads
				(clearance 0)
			)
			(min_thickness 0.25)
			(keepout
				(tracks not_allowed)
				(vias allowed)
				(pads allowed)
				(copperpour not_allowed)
				(footprints allowed)
			)
			(placement
				(enabled no)
				(sheetname "")
			)
			(fill
				(thermal_gap 0.5)
				(thermal_bridge_width 0.5)
				(island_removal_mode 0)
			)
			(polygon
				(pts
					(xy 477.9645 -143.129) (xy 477.9645 -142.621) (xy 478.3455 -142.621) (xy 478.3455 -143.129)
				)
			)
		)
		(zone
			(layer "F.Cu")
			(hatch none 0.5)
			(connect_pads
				(clearance 0)
			)
			(min_thickness 0.25)
			(keepout
				(tracks allowed)
				(vias not_allowed)
				(pads allowed)
				(copperpour not_allowed)
				(footprints allowed)
			)
			(placement
				(enabled no)
				(sheetname "")
			)
			(fill
				(thermal_gap 0.5)
				(thermal_bridge_width 0.5)
				(island_removal_mode 0)
			)
			(polygon
				(pts
					(xy 478.3455 -143.129) (xy 478.3455 -142.621) (xy 477.9645 -142.621) (xy 477.9645 -143.129)
				)
			)
		)
	)
	(footprint ""
		(layer "F.Cu")
		(at 490.3724 -59.944 180)
		(property "Reference" "C30W7"
			(at 0 0 180)
			(layer "F.SilkS")
			(hide yes)
			(effects
				(font
					(size 1.27 1.27)
				)
			)
		)
		(property "Value" "*"
			(at -0.0762 -6.2357 180)
			(unlocked yes)
			(layer "F.Fab")
			(hide yes)
			(effects
				(font
					(size 1.27 1.016)
					(thickness 0.1524)
				)
			)
		)
		(property "Device Type" "SC22U16V5MX-4-GP_SMD-BCG5-SC22A"
			(at -0.0762 -8.2677 180)
			(unlocked yes)
			(layer "F.Fab")
			(hide yes)
			(effects
				(font
					(size 1.27 1.016)
					(thickness 0.1524)
				)
			)
		)
		(duplicate_pad_numbers_are_jumpers no)
		(fp_line
			(start 0.635 0)
			(end -0.635 0)
			(stroke
				(width 0.508)
				(type default)
			)
			(layer "F.SilkS")
		)
		(fp_rect
			(start -0.9652 1.778)
			(end 0.9652 -1.778)
			(stroke
				(width 0)
				(type default)
			)
			(fill no)
			(layer "F.CrtYd")
		)
		(fp_poly
			(pts
				(xy -0.9652 -1.778) (xy 0.9652 -1.778) (xy 0.9652 1.778) (xy -0.9652 1.778)
			)
			(stroke
				(width 0)
				(type default)
			)
			(fill no)
			(layer "F.Fab")
		)
		(pad "1" smd rect
			(at 0 -0.9652 180)
			(size 1.397 1.143)
			(layers "F.Cu" "F.Mask" "F.Paste")
			(net "P5V_STBY_USBC")
		)
		(pad "2" smd rect
			(at 0 0.9652 180)
			(size 1.397 1.143)
			(layers "F.Cu" "F.Mask" "F.Paste")
			(net "GND")
		)
	)
	(footprint ""
		(layer "F.Cu")
		(at 344.043 -127.4572 90)
		(property "Reference" "R7B14"
			(at 0 0 90)
			(layer "F.SilkS")
			(hide yes)
			(effects
				(font
					(size 1.27 1.27)
				)
			)
		)
		(property "Value" ""
			(at 0 0 90)
			(layer "F.Fab")
			(effects
				(font
					(size 1.27 1.27)
				)
			)
		)
		(duplicate_pad_numbers_are_jumpers no)
		(fp_poly
			(pts
				(xy -0.2794 -0.1016) (xy 0.2794 -0.1016) (xy 0.2794 0.9906) (xy -0.2794 0.9906)
			)
			(stroke
				(width 0)
				(type default)
			)
			(fill no)
			(layer "F.CrtYd")
		)
		(fp_line
			(start 0.2794 -0.1016)
			(end -0.2794 -0.1016)
			(stroke
				(width 0.1)
				(type default)
			)
			(layer "F.Fab")
		)
		(fp_line
			(start -0.2794 -0.1016)
			(end -0.2794 0.9906)
			(stroke
				(width 0.1)
				(type default)
			)
			(layer "F.Fab")
		)
		(fp_line
			(start 0.2794 0.9906)
			(end 0.2794 -0.1016)
			(stroke
				(width 0.1)
				(type default)
			)
			(layer "F.Fab")
		)
		(fp_line
			(start -0.2794 0.9906)
			(end 0.2794 0.9906)
			(stroke
				(width 0.1)
				(type default)
			)
			(layer "F.Fab")
		)
		(pad "1" smd rect
			(at 0 0 90)
			(size 0.508 0.508)
			(layers "F.Cu" "F.Mask" "F.Paste")
			(net "VR_PVPP_DEF_ISET")
		)
		(pad "2" smd rect
			(at 0 0.889 90)
			(size 0.508 0.508)
			(layers "F.Cu" "F.Mask" "F.Paste")
			(net "AGND_PVPP_DEF")
		)
		(zone
			(layer "F.Cu")
			(hatch none 0.5)
			(connect_pads
				(clearance 0)
			)
			(min_thickness 0.25)
			(keepout
				(tracks allowed)
				(vias not_allowed)
				(pads allowed)
				(copperpour not_allowed)
				(footprints allowed)
			)
			(placement
				(enabled no)
				(sheetname "")
			)
			(fill
				(thermal_gap 0.5)
				(thermal_bridge_width 0.5)
				(island_removal_mode 0)
			)
			(polygon
				(pts
					(xy 344.297 -127.2032) (xy 344.297 -127.7112) (xy 344.678 -127.7112) (xy 344.678 -127.2032)
				)
			)
		)
		(zone
			(layer "F.Cu")
			(hatch none 0.5)
			(connect_pads
				(clearance 0)
			)
			(min_thickness 0.25)
			(keepout
				(tracks not_allowed)
				(vias allowed)
				(pads allowed)
				(copperpour not_allowed)
				(footprints allowed)
			)
			(placement
				(enabled no)
				(sheetname "")
			)
			(fill
				(thermal_gap 0.5)
				(thermal_bridge_width 0.5)
				(island_removal_mode 0)
			)
			(polygon
				(pts
					(xy 344.678 -127.2032) (xy 344.678 -127.7112) (xy 344.297 -127.7112) (xy 344.297 -127.2032)
				)
			)
		)
	)
)
